(kicad_pcb
	(version 20260206)
	(generator "pcbnew")
	(generator_version "10.0")
	(general
		(thickness 1.6)
		(legacy_teardrops no)
	)
	(paper "A4")
	(title_block
		(title "timecard-production-celestica-r4006 — R4006-B0001-02_R01.brd")
		(comment 1 "Time Appliance Project (Time Card) / footprints 127-130 of 1113")
	)
	(layers
		(0 "F.Cu" signal "TOP")
		(4 "In1.Cu" signal "L02_GND1")
		(6 "In2.Cu" signal "L03_SIG1")
		(8 "In3.Cu" signal "L04_GND2")
		(10 "In4.Cu" signal "L05_VCC1")
		(12 "In5.Cu" signal "L06_VCC2")
		(14 "In6.Cu" signal "L07_GND3")
		(16 "In7.Cu" signal "L08_SIG2")
		(18 "In8.Cu" signal "L09_GND4")
		(2 "B.Cu" signal "BOTTOM")
		(9 "F.Adhes" user "F.Adhesive")
		(11 "B.Adhes" user "B.Adhesive")
		(13 "F.Paste" user "Package Geometry/Pastemask Top")
		(15 "B.Paste" user "Package Geometry/Pastemask Bottom")
		(5 "F.SilkS" user "Ref Des/Silkscreen Top")
		(7 "B.SilkS" user "Ref Des/Silkscreen Bottom")
		(1 "F.Mask" user "Board Geometry/Soldermask Top")
		(3 "B.Mask" user "Board Geometry/Soldermask Bottom")
		(17 "Dwgs.User" user "User.Drawings")
		(19 "Cmts.User" user "User.Comments")
		(21 "Eco1.User" user "User.Eco1")
		(23 "Eco2.User" user "User.Eco2")
		(25 "Edge.Cuts" user "Board Geometry/Outline")
		(27 "Margin" user)
		(31 "F.CrtYd" user "Package Geometry/Place Bound Top")
		(29 "B.CrtYd" user "Package Geometry/Place Bound Bottom")
		(35 "F.Fab" user "Ref Des/Assembly Top")
		(33 "B.Fab" user "Ref Des/Assembly Bottom")
	)
	(footprint ""
		(layer "F.Cu")
		(at 113.919 -61.976 90)
		(property "Reference" "R234"
			(at 3.302 0.29337 90)
			(unlocked yes)
			(layer "F.SilkS")
			(effects
				(font
					(size 0.7874 0.5842)
					(thickness 0.1524)
				)
			)
		)
		(property "Value" "VAL*"
			(at 0.02032 2.13233 90)
			(unlocked yes)
			(layer "F.Fab")
			(hide yes)
			(effects
				(font
					(size 0.7874 0.5842)
					(thickness 0.1524)
				)
			)
		)
		(property "Tolerance" "TOL*"
			(at 0.044704 3.05435 90)
			(unlocked yes)
			(layer "Cmts.User")
			(hide yes)
			(effects
				(font
					(size 0.7874 0.5842)
					(thickness 0.1524)
				)
			)
		)
		(property "User Part Number" "PARTNUM*"
			(at 0.02032 4.024884 90)
			(unlocked yes)
			(layer "Cmts.User")
			(hide yes)
			(effects
				(font
					(size 0.7874 0.5842)
					(thickness 0.1524)
				)
			)
		)
		(property "Device Type" "RESISTOR-G155-133R0-01,33OHM,1%"
			(at 0.008382 1.210564 90)
			(unlocked yes)
			(layer "F.Fab")
			(hide yes)
			(effects
				(font
					(size 0.7874 0.5842)
					(thickness 0.1524)
				)
			)
		)
		(duplicate_pad_numbers_are_jumpers no)
		(fp_line
			(start 1.143 -0.5588)
			(end -1.143 -0.5588)
			(stroke
				(width 0.1)
				(type default)
			)
			(layer "F.SilkS")
		)
		(fp_line
			(start -1.143 -0.5588)
			(end -1.143 0.5588)
			(stroke
				(width 0.1)
				(type default)
			)
			(layer "F.SilkS")
		)
		(fp_line
			(start 1.143 0.5588)
			(end 1.143 -0.5588)
			(stroke
				(width 0.1)
				(type default)
			)
			(layer "F.SilkS")
		)
		(fp_line
			(start -1.143 0.5588)
			(end 1.143 0.5588)
			(stroke
				(width 0.1)
				(type default)
			)
			(layer "F.SilkS")
		)
		(fp_poly
			(pts
				(xy -1.143 0.5588) (xy 1.143 0.5588) (xy 1.143 -0.5588) (xy -1.143 -0.5588)
			)
			(stroke
				(width 0)
				(type default)
			)
			(fill no)
			(layer "F.CrtYd")
		)
		(fp_line
			(start 0.508 -0.3048)
			(end -0.508 -0.3048)
			(stroke
				(width 0.1)
				(type default)
			)
			(layer "F.Fab")
		)
		(fp_line
			(start -0.508 -0.3048)
			(end -0.508 0.3048)
			(stroke
				(width 0.1)
				(type default)
			)
			(layer "F.Fab")
		)
		(fp_line
			(start 0.508 0.3048)
			(end 0.508 -0.3048)
			(stroke
				(width 0.1)
				(type default)
			)
			(layer "F.Fab")
		)
		(fp_line
			(start -0.508 0.3048)
			(end 0.508 0.3048)
			(stroke
				(width 0.1)
				(type default)
			)
			(layer "F.Fab")
		)
		(pad "1" smd rect
			(at -0.5334 0 90)
			(size 0.7112 0.6096)
			(layers "F.Cu" "F.Mask" "F.Paste")
			(net "FPGA_D00_MOSI")
		)
		(pad "2" smd rect
			(at 0.5334 0 90)
			(size 0.7112 0.6096)
			(layers "F.Cu" "F.Mask" "F.Paste")
			(net "FPGA_FLASH_DQ0_MOSI")
		)
		(zone
			(layer "F.Cu")
			(hatch none 0.5)
			(connect_pads
				(clearance 0)
			)
			(min_thickness 0.25)
			(keepout
				(tracks allowed)
				(vias not_allowed)
				(pads allowed)
				(copperpour not_allowed)
				(footprints allowed)
			)
			(placement
				(enabled no)
				(sheetname "")
			)
			(fill
				(thermal_gap 0.5)
				(thermal_bridge_width 0.5)
				(island_removal_mode 0)
			)
			(polygon
				(pts
					(xy 114.2238 -61.8998) (xy 114.2238 -62.0522) (xy 113.6142 -62.0522) (xy 113.6142 -61.8998)
				)
			)
		)
		(zone
			(layer "F.Cu")
			(hatch none 0.5)
			(connect_pads
				(clearance 0)
			)
			(min_thickness 0.25)
			(keepout
				(tracks not_allowed)
				(vias allowed)
				(pads allowed)
				(copperpour not_allowed)
				(footprints allowed)
			)
			(placement
				(enabled no)
				(sheetname "")
			)
			(fill
				(thermal_gap 0.5)
				(thermal_bridge_width 0.5)
				(island_removal_mode 0)
			)
			(polygon
				(pts
					(xy 114.2238 -61.8998) (xy 114.2238 -62.0522) (xy 113.6142 -62.0522) (xy 113.6142 -61.8998)
				)
			)
		)
	)
	(footprint ""
		(layer "F.Cu")
		(at 163.926774 -53.600096 90)
		(property "Reference" "J11"
			(at 5.12953 0.284226 0)
			(unlocked yes)
			(layer "F.SilkS")
			(effects
				(font
					(size 0.7874 0.5842)
					(thickness 0.1524)
				)
			)
		)
		(property "Value" ""
			(at 0 0 90)
			(layer "F.Fab")
			(effects
				(font
					(size 1.27 1.27)
				)
			)
		)
		(property "User Part Number" "PARTNUM*"
			(at 0.205486 7.130034 90)
			(unlocked yes)
			(layer "Cmts.User")
			(hide yes)
			(effects
				(font
					(size 0.7874 0.5842)
					(thickness 0.1524)
				)
			)
		)
		(property "Device Type" "CONN_USB_1X5_G2_GH4_F_RA_SMT-GA"
			(at 0.205486 5.936234 90)
			(unlocked yes)
			(layer "F.Fab")
			(hide yes)
			(effects
				(font
					(size 0.7874 0.5842)
					(thickness 0.1524)
				)
			)
		)
		(duplicate_pad_numbers_are_jumpers no)
		(fp_line
			(start 4.354068 -2.102866)
			(end 4.354068 4.129024)
			(stroke
				(width 0.1)
				(type default)
			)
			(layer "F.SilkS")
		)
		(fp_line
			(start -4.354068 -2.102866)
			(end 4.354068 -2.102866)
			(stroke
				(width 0.1)
				(type default)
			)
			(layer "F.SilkS")
		)
		(fp_line
			(start 4.354068 4.129024)
			(end -4.354068 4.129024)
			(stroke
				(width 0.1)
				(type default)
			)
			(layer "F.SilkS")
		)
		(fp_line
			(start -4.354068 4.129024)
			(end -4.354068 -2.102866)
			(stroke
				(width 0.1)
				(type default)
			)
			(layer "F.SilkS")
		)
		(fp_rect
			(start -9.18972 -6.928866)
			(end 9.18972 7.607554)
			(stroke
				(width 0)
				(type default)
			)
			(fill no)
			(layer "B.CrtYd")
		)
		(fp_rect
			(start -4.608068 -2.356866)
			(end 4.608068 4.383024)
			(stroke
				(width 0)
				(type default)
			)
			(fill no)
			(layer "F.CrtYd")
		)
		(fp_line
			(start 3.849878 -1.42494)
			(end 3.849878 3.875024)
			(stroke
				(width 0.1)
				(type default)
			)
			(layer "F.Fab")
		)
		(fp_line
			(start -3.849878 -1.42494)
			(end 3.849878 -1.42494)
			(stroke
				(width 0.1)
				(type default)
			)
			(layer "F.Fab")
		)
		(fp_line
			(start 3.849878 3.875024)
			(end -3.849878 3.875024)
			(stroke
				(width 0.1)
				(type default)
			)
			(layer "F.Fab")
		)
		(fp_line
			(start -3.849878 3.875024)
			(end -3.849878 -1.42494)
			(stroke
				(width 0.1)
				(type default)
			)
			(layer "F.Fab")
		)
		(fp_text user "1"
			(at -1.442466 -2.636774 0)
			(unlocked yes)
			(layer "F.SilkS")
			(effects
				(font
					(size 0.7874 0.5842)
					(thickness 0.1524)
				)
			)
		)
		(fp_text user "5"
			(at 1.986534 -2.509774 0)
			(unlocked yes)
			(layer "F.SilkS")
			(effects
				(font
					(size 0.7874 0.5842)
					(thickness 0.1524)
				)
			)
		)
		(fp_text user "GH2"
			(at 5.6769 -1.708404 90)
			(unlocked yes)
			(layer "F.SilkS")
			(effects
				(font
					(size 0.7874 0.5842)
					(thickness 0.1524)
				)
			)
		)
		(fp_text user "GH1"
			(at -5.467096 -1.581404 90)
			(unlocked yes)
			(layer "F.SilkS")
			(effects
				(font
					(size 0.7874 0.5842)
					(thickness 0.1524)
				)
			)
		)
		(fp_text user "GH3"
			(at -5.467096 1.720596 90)
			(unlocked yes)
			(layer "F.SilkS")
			(effects
				(font
					(size 0.7874 0.5842)
					(thickness 0.1524)
				)
			)
		)
		(fp_text user "GH4"
			(at 5.6769 1.974596 90)
			(unlocked yes)
			(layer "F.SilkS")
			(effects
				(font
					(size 0.7874 0.5842)
					(thickness 0.1524)
				)
			)
		)
		(fp_text user "1"
			(at -1.403096 -2.343404 90)
			(unlocked yes)
			(layer "F.Fab")
			(effects
				(font
					(size 0.7874 0.5842)
					(thickness 0.1524)
				)
			)
		)
		(fp_text user "5"
			(at 1.430274 -2.29997 90)
			(unlocked yes)
			(layer "F.Fab")
			(effects
				(font
					(size 0.7874 0.5842)
					(thickness 0.1524)
				)
			)
		)
		(fp_text user "GH1"
			(at -2.806954 -2.080768 90)
			(unlocked yes)
			(layer "F.Fab")
			(effects
				(font
					(size 0.7874 0.5842)
					(thickness 0.1524)
				)
			)
		)
		(fp_text user "GH2"
			(at 3.168904 -1.962404 90)
			(unlocked yes)
			(layer "F.Fab")
			(effects
				(font
					(size 0.7874 0.5842)
					(thickness 0.1524)
				)
			)
		)
		(fp_text user "GH4"
			(at 5.2959 2.088896 90)
			(unlocked yes)
			(layer "F.Fab")
			(effects
				(font
					(size 0.7874 0.5842)
					(thickness 0.1524)
				)
			)
		)
		(fp_text user "GH3"
			(at -5.2451 2.215896 90)
			(unlocked yes)
			(layer "F.Fab")
			(effects
				(font
					(size 0.7874 0.5842)
					(thickness 0.1524)
				)
			)
		)
		(fp_text user "G2"
			(at 1.14935 3.052318 90)
			(unlocked yes)
			(layer "F.Fab")
			(effects
				(font
					(size 0.7874 0.5842)
					(thickness 0.1524)
				)
			)
		)
		(fp_text user "G1"
			(at -0.88773 3.07086 90)
			(unlocked yes)
			(layer "F.Fab")
			(effects
				(font
					(size 0.7874 0.5842)
					(thickness 0.1524)
				)
			)
		)
		(pad "1" smd rect
			(at -1.299972 -1.100074 90)
			(size 0.4064 1.3462)
			(layers "F.Cu" "F.Mask" "F.Paste")
			(net "XP5R0V_USB_CONN")
		)
		(pad "2" smd rect
			(at -0.649986 -1.100074 90)
			(size 0.4064 1.3462)
			(layers "F.Cu" "F.Mask" "F.Paste")
			(net "CONN_MICRO_USB_DM")
		)
		(pad "3" smd rect
			(at 0 -1.100074 90)
			(size 0.4064 1.3462)
			(layers "F.Cu" "F.Mask" "F.Paste")
			(net "CONN_MICRO_USB_DP")
		)
		(pad "4" smd rect
			(at 0.649986 -1.100074 90)
			(size 0.4064 1.3462)
			(layers "F.Cu" "F.Mask" "F.Paste")
			(net "Net_748")
		)
		(pad "5" smd rect
			(at 1.299972 -1.100074 90)
			(size 0.4064 1.3462)
			(layers "F.Cu" "F.Mask" "F.Paste")
			(net "SG")
		)
		(pad "G1" smd rect
			(at -0.999998 1.575054 90)
			(size 1.4986 1.905)
			(layers "F.Cu" "F.Mask" "F.Paste")
			(net "SG")
		)
		(pad "G2" smd rect
			(at 0.999998 1.575054 90)
			(size 1.4986 1.905)
			(layers "F.Cu" "F.Mask" "F.Paste")
			(net "SG")
		)
		(pad "GH1" thru_hole circle
			(at -2.500122 -1.124966 90)
			(size 1.4478 1.4478)
			(drill 0.8382)
			(layers "*.Cu" "*.Mask")
			(remove_unused_layers no)
			(net "SG")
			(padstack
				(mode front_inner_back)
				(layer "Inner"
					(shape circle)
					(size 1.4478 1.4478)
					(clearance -0.0127)
				)
				(layer "B.Cu"
					(shape circle)
					(size 1.4478 1.4478)
				)
			)
		)
		(pad "GH2" thru_hole circle
			(at 2.500122 -1.124966 90)
			(size 1.4478 1.4478)
			(drill 0.8382)
			(layers "*.Cu" "*.Mask")
			(remove_unused_layers no)
			(net "SG")
			(padstack
				(mode front_inner_back)
				(layer "Inner"
					(shape circle)
					(size 1.4478 1.4478)
					(clearance -0.0127)
				)
				(layer "B.Cu"
					(shape circle)
					(size 1.4478 1.4478)
				)
			)
		)
		(pad "GH3" thru_hole circle
			(at -3.50012 1.575054 90)
			(size 0 0)
			(drill oval 0.6096 1.2954)
			(layers "*.Cu" "*.Mask")
			(remove_unused_layers no)
			(net "SG")
			(padstack
				(mode front_inner_back)
				(layer "Inner"
					(shape oval)
					(size 1.2192 1.905)
					(clearance -0.0127)
				)
				(layer "B.Cu"
					(shape oval)
					(size 1.2192 1.905)
				)
			)
		)
		(pad "GH4" thru_hole circle
			(at 3.50012 1.575054 90)
			(size 0 0)
			(drill oval 0.6096 1.2954)
			(layers "*.Cu" "*.Mask")
			(remove_unused_layers no)
			(net "SG")
			(padstack
				(mode front_inner_back)
				(layer "Inner"
					(shape oval)
					(size 1.2192 1.905)
					(clearance -0.0127)
				)
				(layer "B.Cu"
					(shape oval)
					(size 1.2192 1.905)
				)
			)
		)
	)
	(footprint ""
		(layer "F.Cu")
		(at 135.6614 -100.5078)
		(property "Reference" "R11"
			(at -2.0574 -0.29083 0)
			(unlocked yes)
			(layer "F.SilkS")
			(effects
				(font
					(size 0.7874 0.5842)
					(thickness 0.1524)
				)
			)
		)
		(property "Value" "VAL*"
			(at 0.02032 2.13233 0)
			(unlocked yes)
			(layer "F.Fab")
			(hide yes)
			(effects
				(font
					(size 0.7874 0.5842)
					(thickness 0.1524)
				)
			)
		)
		(property "Device Type" "RESISTOR-G155-01203-01,120KOHMA"
			(at 0.008382 1.210564 0)
			(unlocked yes)
			(layer "F.Fab")
			(hide yes)
			(effects
				(font
					(size 0.7874 0.5842)
					(thickness 0.1524)
				)
			)
		)
		(property "User Part Number" "PARTNUM*"
			(at 0.02032 4.024884 0)
			(unlocked yes)
			(layer "Cmts.User")
			(hide yes)
			(effects
				(font
					(size 0.7874 0.5842)
					(thickness 0.1524)
				)
			)
		)
		(property "Tolerance" "TOL*"
			(at 0.044704 3.05435 0)
			(unlocked yes)
			(layer "Cmts.User")
			(hide yes)
			(effects
				(font
					(size 0.7874 0.5842)
					(thickness 0.1524)
				)
			)
		)
		(duplicate_pad_numbers_are_jumpers no)
		(fp_line
			(start -1.143 -0.5588)
			(end -1.143 0.5588)
			(stroke
				(width 0.1)
				(type default)
			)
			(layer "F.SilkS")
		)
		(fp_line
			(start -1.143 0.5588)
			(end 1.143 0.5588)
			(stroke
				(width 0.1)
				(type default)
			)
			(layer "F.SilkS")
		)
		(fp_line
			(start 1.143 -0.5588)
			(end -1.143 -0.5588)
			(stroke
				(width 0.1)
				(type default)
			)
			(layer "F.SilkS")
		)
		(fp_line
			(start 1.143 0.5588)
			(end 1.143 -0.5588)
			(stroke
				(width 0.1)
				(type default)
			)
			(layer "F.SilkS")
		)
		(fp_rect
			(start -1.143 0.5588)
			(end 1.143 -0.5588)
			(stroke
				(width 0)
				(type default)
			)
			(fill no)
			(layer "F.CrtYd")
		)
		(fp_line
			(start -0.508 -0.3048)
			(end -0.508 0.3048)
			(stroke
				(width 0.1)
				(type default)
			)
			(layer "F.Fab")
		)
		(fp_line
			(start -0.508 0.3048)
			(end 0.508 0.3048)
			(stroke
				(width 0.1)
				(type default)
			)
			(layer "F.Fab")
		)
		(fp_line
			(start 0.508 -0.3048)
			(end -0.508 -0.3048)
			(stroke
				(width 0.1)
				(type default)
			)
			(layer "F.Fab")
		)
		(fp_line
			(start 0.508 0.3048)
			(end 0.508 -0.3048)
			(stroke
				(width 0.1)
				(type default)
			)
			(layer "F.Fab")
		)
		(pad "1" smd rect
			(at -0.5334 0)
			(size 0.7112 0.6096)
			(layers "F.Cu" "F.Mask" "F.Paste")
			(net "XP12R0V_IN")
		)
		(pad "2" smd rect
			(at 0.5334 0)
			(size 0.7112 0.6096)
			(layers "F.Cu" "F.Mask" "F.Paste")
			(net "XP12R0V_A_OV")
		)
		(zone
			(layer "F.Cu")
			(hatch none 0.5)
			(connect_pads
				(clearance 0)
			)
			(min_thickness 0.25)
			(keepout
				(tracks allowed)
				(vias not_allowed)
				(pads allowed)
				(copperpour not_allowed)
				(footprints allowed)
			)
			(placement
				(enabled no)
				(sheetname "")
			)
			(fill
				(thermal_gap 0.5)
				(thermal_bridge_width 0.5)
				(island_removal_mode 0)
			)
			(polygon
				(pts
					(xy 135.5852 -100.203) (xy 135.7376 -100.203) (xy 135.7376 -100.8126) (xy 135.5852 -100.8126)
				)
			)
		)
	)
	(footprint ""
		(layer "F.Cu")
		(at 105.8418 -72.517 180)
		(property "Reference" "C240"
			(at -0.3302 -4.09067 0)
			(unlocked yes)
			(layer "F.SilkS")
			(effects
				(font
					(size 0.7874 0.5842)
					(thickness 0.1524)
				)
			)
		)
		(property "Value" "VAL*"
			(at 0.0762 3.134106 180)
			(unlocked yes)
			(layer "F.Fab")
			(hide yes)
			(effects
				(font
					(size 0.7874 0.5842)
					(thickness 0.1524)
				)
			)
		)
		(property "Device Type" "CAPACITOR-G107-0F226-CM,22UF,2A"
			(at 0.0508 2.194306 180)
			(unlocked yes)
			(layer "F.Fab")
			(hide yes)
			(effects
				(font
					(size 0.7874 0.5842)
					(thickness 0.1524)
				)
			)
		)
		(property "User Part Number" "PARTNUM*"
			(at 0.1016 5.013706 180)
			(unlocked yes)
			(layer "Cmts.User")
			(hide yes)
			(effects
				(font
					(size 0.7874 0.5842)
					(thickness 0.1524)
				)
			)
		)
		(property "Tolerance" "TOL*"
			(at 0.0762 4.048506 180)
			(unlocked yes)
			(layer "Cmts.User")
			(hide yes)
			(effects
				(font
					(size 0.7874 0.5842)
					(thickness 0.1524)
				)
			)
		)
		(duplicate_pad_numbers_are_jumpers no)
		(fp_line
			(start 1.5748 0.9398)
			(end 1.5748 -0.9398)
			(stroke
				(width 0.1)
				(type default)
			)
			(layer "F.SilkS")
		)
		(fp_line
			(start 1.5748 -0.9398)
			(end -1.5748 -0.9398)
			(stroke
				(width 0.1)
				(type default)
			)
			(layer "F.SilkS")
		)
		(fp_line
			(start -1.5748 0.9398)
			(end 1.5748 0.9398)
			(stroke
				(width 0.1)
				(type default)
			)
			(layer "F.SilkS")
		)
		(fp_line
			(start -1.5748 -0.9398)
			(end -1.5748 0.9398)
			(stroke
				(width 0.1)
				(type default)
			)
			(layer "F.SilkS")
		)
		(fp_rect
			(start -1.5748 0.9398)
			(end 1.5748 -0.9398)
			(stroke
				(width 0)
				(type default)
			)
			(fill no)
			(layer "F.CrtYd")
		)
		(fp_line
			(start 1.016 0.635)
			(end 1.016 -0.635)
			(stroke
				(width 0.1)
				(type default)
			)
			(layer "F.Fab")
		)
		(fp_line
			(start 1.016 -0.635)
			(end -1.016 -0.635)
			(stroke
				(width 0.1)
				(type default)
			)
			(layer "F.Fab")
		)
		(fp_line
			(start -1.016 0.635)
			(end 1.016 0.635)
			(stroke
				(width 0.1)
				(type default)
			)
			(layer "F.Fab")
		)
		(fp_line
			(start -1.016 -0.635)
			(end -1.016 0.635)
			(stroke
				(width 0.1)
				(type default)
			)
			(layer "F.Fab")
		)
		(pad "1" smd rect
			(at -0.8382 0 180)
			(size 0.9652 1.3716)
			(layers "F.Cu" "F.Mask" "F.Paste")
			(net "XP3R3V_FPGA")
		)
		(pad "2" smd rect
			(at 0.8382 0 180)
			(size 0.9652 1.3716)
			(layers "F.Cu" "F.Mask" "F.Paste")
			(net "SG")
		)
		(zone
			(layer "F.Cu")
			(hatch none 0.5)
			(connect_pads
				(clearance 0)
			)
			(min_thickness 0.25)
			(keepout
				(tracks allowed)
				(vias not_allowed)
				(pads allowed)
				(copperpour not_allowed)
				(footprints allowed)
			)
			(placement
				(enabled no)
				(sheetname "")
			)
			(fill
				(thermal_gap 0.5)
				(thermal_bridge_width 0.5)
				(island_removal_mode 0)
			)
			(polygon
				(pts
					(xy 106.0704 -73.152) (xy 105.6132 -73.152) (xy 105.6132 -71.882) (xy 106.0704 -71.882)
				)
			)
		)
	)
)
